# S9S_MB_2U (Grand Teton) — schematic netlist excerpt (pin names and nets, part order shuffled) for the footprints in the layout excerpt that follows; sources: Cadence DE-HDL packaged netlist, KiCad conversion of 03242023_DA0F0TMBIJ0_F0T_Motherboard_J_brd_V01_OCP.brd

PR3920  Q_RES  0 5% CHIP  pkg 0402LF  page 302 : A = HSC_FLT_TYPE_1 ; B = HSC_FLT_TYPE
PC249  Q_CAP  2.2UF 10V 10% X6S  pkg C0402  page 269 : A = PVCCIN_CPU0_VDD5 ; B = GND

(kicad_pcb
	(version 20260206)
	(generator "pcbnew")
	(generator_version "10.0")
	(general
		(thickness 1.6)
		(legacy_teardrops no)
	)
	(paper "A4")
	(title_block
		(title "03242023_DA0F0TMBIJ0_F0T_Motherboard_J_brd_V01_OCP.brd")
		(comment 1 "Grand Teton / footprints 1770-1771 of 6105")
	)
	(layers
		(0 "F.Cu" signal "TOP")
		(4 "In1.Cu" signal "GND")
		(6 "In2.Cu" signal "IN1")
		(8 "In3.Cu" signal "GND1")
		(10 "In4.Cu" signal "IN2")
		(12 "In5.Cu" signal "GND2")
		(14 "In6.Cu" signal "IN3")
		(16 "In7.Cu" signal "GND3")
		(18 "In8.Cu" signal "VCC")
		(20 "In9.Cu" signal "VCC1")
		(22 "In10.Cu" signal "GND4")
		(24 "In11.Cu" signal "IN4")
		(26 "In12.Cu" signal "GND5")
		(28 "In13.Cu" signal "IN5")
		(30 "In14.Cu" signal "GND6")
		(32 "In15.Cu" signal "IN6")
		(34 "In16.Cu" signal "GND7")
		(2 "B.Cu" signal "BOTTOM")
		(9 "F.Adhes" user "F.Adhesive")
		(11 "B.Adhes" user "B.Adhesive")
		(13 "F.Paste" user "Package Geometry/Pastemask Top")
		(15 "B.Paste" user "Package Geometry/Pastemask Bottom")
		(5 "F.SilkS" user "Ref Des/Silkscreen Top")
		(7 "B.SilkS" user "Ref Des/Silkscreen Bottom")
		(1 "F.Mask" user "Board Geometry/Soldermask Top")
		(3 "B.Mask" user "Board Geometry/Soldermask Bottom")
		(17 "Dwgs.User" user "User.Drawings")
		(19 "Cmts.User" user "User.Comments")
		(21 "Eco1.User" user "User.Eco1")
		(23 "Eco2.User" user "User.Eco2")
		(25 "Edge.Cuts" user "Board Geometry/Outline")
		(27 "Margin" user)
		(31 "F.CrtYd" user "Package Geometry/Place Bound Top")
		(29 "B.CrtYd" user "Package Geometry/Place Bound Bottom")
		(35 "F.Fab" user "Ref Des/Assembly Top")
		(33 "B.Fab" user "Ref Des/Assembly Bottom")
	)
	(footprint ""
		(layer "F.Cu")
		(at 205.397608 -406.855422)
		(property "Reference" "PR3920"
			(at 0 0 0)
			(layer "F.SilkS")
			(hide yes)
			(effects
				(font
					(size 1.27 1.27)
				)
			)
		)
		(property "Value" ""
			(at 0 0 0)
			(layer "F.Fab")
			(effects
				(font
					(size 1.27 1.27)
				)
			)
		)
		(duplicate_pad_numbers_are_jumpers no)
		(fp_line
			(start -0.7874 -0.4064)
			(end 0.7874 -0.4064)
			(stroke
				(width 0.1524)
				(type default)
			)
			(layer "F.SilkS")
		)
		(fp_line
			(start -0.7874 0.4064)
			(end -0.7874 -0.4064)
			(stroke
				(width 0.1524)
				(type default)
			)
			(layer "F.SilkS")
		)
		(fp_line
			(start 0.7874 -0.4064)
			(end 0.7874 0.4064)
			(stroke
				(width 0.1524)
				(type default)
			)
			(layer "F.SilkS")
		)
		(fp_line
			(start 0.7874 0.4064)
			(end -0.7874 0.4064)
			(stroke
				(width 0.1524)
				(type default)
			)
			(layer "F.SilkS")
		)
		(fp_line
			(start -0.67945 -0.305054)
			(end -0.12065 -0.305054)
			(stroke
				(width 0.1)
				(type default)
			)
			(layer "F.Fab")
		)
		(fp_line
			(start -0.67945 0.3048)
			(end -0.67945 -0.305054)
			(stroke
				(width 0.1)
				(type default)
			)
			(layer "F.Fab")
		)
		(fp_line
			(start -0.12065 -0.305054)
			(end -0.12065 -0.2794)
			(stroke
				(width 0.1)
				(type default)
			)
			(layer "F.Fab")
		)
		(fp_line
			(start -0.12065 -0.2794)
			(end 0.12065 -0.2794)
			(stroke
				(width 0.1)
				(type default)
			)
			(layer "F.Fab")
		)
		(fp_line
			(start -0.12065 0.2794)
			(end -0.12065 0.3048)
			(stroke
				(width 0.1)
				(type default)
			)
			(layer "F.Fab")
		)
		(fp_line
			(start -0.12065 0.3048)
			(end -0.67945 0.3048)
			(stroke
				(width 0.1)
				(type default)
			)
			(layer "F.Fab")
		)
		(fp_line
			(start 0.120396 0.2794)
			(end -0.12065 0.2794)
			(stroke
				(width 0.1)
				(type default)
			)
			(layer "F.Fab")
		)
		(fp_line
			(start 0.120396 0.3048)
			(end 0.120396 0.2794)
			(stroke
				(width 0.1)
				(type default)
			)
			(layer "F.Fab")
		)
		(fp_line
			(start 0.12065 -0.3048)
			(end 0.67945 -0.3048)
			(stroke
				(width 0.1)
				(type default)
			)
			(layer "F.Fab")
		)
		(fp_line
			(start 0.12065 -0.2794)
			(end 0.12065 -0.3048)
			(stroke
				(width 0.1)
				(type default)
			)
			(layer "F.Fab")
		)
		(fp_line
			(start 0.67945 -0.3048)
			(end 0.67945 0.3048)
			(stroke
				(width 0.1)
				(type default)
			)
			(layer "F.Fab")
		)
		(fp_line
			(start 0.67945 0.3048)
			(end 0.120396 0.3048)
			(stroke
				(width 0.1)
				(type default)
			)
			(layer "F.Fab")
		)
		(pad "1" smd circle
			(at -0.40005 0)
			(size 0 0)
			(layers "F.Cu" "F.Mask" "F.Paste")
			(net "HSC_FLT_TYPE_1")
		)
		(pad "2" smd circle
			(at 0.40005 0)
			(size 0 0)
			(layers "F.Cu" "F.Mask" "F.Paste")
			(net "HSC_FLT_TYPE")
		)
	)
	(footprint ""
		(layer "F.Cu")
		(at 374.00484 -339.602572 90)
		(property "Reference" "PC249"
			(at 0 0 90)
			(layer "F.SilkS")
			(hide yes)
			(effects
				(font
					(size 1.27 1.27)
				)
			)
		)
		(property "Value" ""
			(at 0 0 90)
			(layer "F.Fab")
			(effects
				(font
					(size 1.27 1.27)
				)
			)
		)
		(duplicate_pad_numbers_are_jumpers no)
		(fp_line
			(start 0.7874 -0.4064)
			(end 0.7874 0.4064)
			(stroke
				(width 0.1524)
				(type default)
			)
			(layer "F.SilkS")
		)
		(fp_line
			(start -0.7874 -0.4064)
			(end 0.7874 -0.4064)
			(stroke
				(width 0.1524)
				(type default)
			)
			(layer "F.SilkS")
		)
		(fp_line
			(start 0.7874 0.4064)
			(end -0.7874 0.4064)
			(stroke
				(width 0.1524)
				(type default)
			)
			(layer "F.SilkS")
		)
		(fp_line
			(start -0.7874 0.4064)
			(end -0.7874 -0.4064)
			(stroke
				(width 0.1524)
				(type default)
			)
			(layer "F.SilkS")
		)
		(fp_line
			(start -0.12065 -0.305054)
			(end -0.12065 -0.2794)
			(stroke
				(width 0.1)
				(type default)
			)
			(layer "F.Fab")
		)
		(fp_line
			(start -0.67945 -0.305054)
			(end -0.12065 -0.305054)
			(stroke
				(width 0.1)
				(type default)
			)
			(layer "F.Fab")
		)
		(fp_line
			(start 0.67945 -0.3048)
			(end 0.67945 0.3048)
			(stroke
				(width 0.1)
				(type default)
			)
			(layer "F.Fab")
		)
		(fp_line
			(start 0.12065 -0.3048)
			(end 0.67945 -0.3048)
			(stroke
				(width 0.1)
				(type default)
			)
			(layer "F.Fab")
		)
		(fp_line
			(start 0.12065 -0.2794)
			(end 0.12065 -0.3048)
			(stroke
				(width 0.1)
				(type default)
			)
			(layer "F.Fab")
		)
		(fp_line
			(start -0.12065 -0.2794)
			(end 0.12065 -0.2794)
			(stroke
				(width 0.1)
				(type default)
			)
			(layer "F.Fab")
		)
		(fp_line
			(start 0.120396 0.2794)
			(end -0.12065 0.2794)
			(stroke
				(width 0.1)
				(type default)
			)
			(layer "F.Fab")
		)
		(fp_line
			(start -0.12065 0.2794)
			(end -0.12065 0.3048)
			(stroke
				(width 0.1)
				(type default)
			)
			(layer "F.Fab")
		)
		(fp_line
			(start 0.67945 0.3048)
			(end 0.120396 0.3048)
			(stroke
				(width 0.1)
				(type default)
			)
			(layer "F.Fab")
		)
		(fp_line
			(start 0.120396 0.3048)
			(end 0.120396 0.2794)
			(stroke
				(width 0.1)
				(type default)
			)
			(layer "F.Fab")
		)
		(fp_line
			(start -0.12065 0.3048)
			(end -0.67945 0.3048)
			(stroke
				(width 0.1)
				(type default)
			)
			(layer "F.Fab")
		)
		(fp_line
			(start -0.67945 0.3048)
			(end -0.67945 -0.305054)
			(stroke
				(width 0.1)
				(type default)
			)
			(layer "F.Fab")
		)
		(pad "1" smd circle
			(at -0.40005 0 90)
			(size 0 0)
			(layers "F.Cu" "F.Mask" "F.Paste")
			(net "PVCCIN_CPU0_VDD5")
		)
		(pad "2" smd circle
			(at 0.40005 0 90)
			(size 0 0)
			(layers "F.Cu" "F.Mask" "F.Paste")
			(net "GND")
		)
	)
)
